(kicad_pcb
	(version 20260206)
	(generator "pcbnew")
	(generator_version "10.0")
	(general
		(thickness 1.6)
		(legacy_teardrops no)
	)
	(paper "A4")
	(title_block
		(title "dpb — 14545-sa.0730WZS0815.brd")
		(comment 1 "Honey Badger (Wiwynn) / footprints 397-399 of 1066")
	)
	(layers
		(0 "F.Cu" signal "TOP")
		(4 "In1.Cu" signal "L2GND")
		(6 "In2.Cu" signal "L3")
		(8 "In3.Cu" signal "L4VCC")
		(10 "In4.Cu" signal "L5VCC")
		(12 "In5.Cu" signal "L6")
		(14 "In6.Cu" signal "L7GND")
		(2 "B.Cu" signal "BOTTOM")
		(9 "F.Adhes" user "F.Adhesive")
		(11 "B.Adhes" user "B.Adhesive")
		(13 "F.Paste" user "Package Geometry/Pastemask Top")
		(15 "B.Paste" user "Package Geometry/Pastemask Bottom")
		(5 "F.SilkS" user "Ref Des/Silkscreen Top")
		(7 "B.SilkS" user "Ref Des/Silkscreen Bottom")
		(1 "F.Mask" user "Board Geometry/Soldermask Top")
		(3 "B.Mask" user "Board Geometry/Soldermask Bottom")
		(17 "Dwgs.User" user "User.Drawings")
		(19 "Cmts.User" user "User.Comments")
		(21 "Eco1.User" user "User.Eco1")
		(23 "Eco2.User" user "User.Eco2")
		(25 "Edge.Cuts" user "Board Geometry/Outline")
		(27 "Margin" user)
		(31 "F.CrtYd" user "Package Geometry/Place Bound Top")
		(29 "B.CrtYd" user "Package Geometry/Place Bound Bottom")
		(35 "F.Fab" user "Ref Des/Assembly Top")
		(33 "B.Fab" user "Ref Des/Assembly Bottom")
	)
	(footprint ""
		(layer "F.Cu")
		(at 17.500092 -438.330086 -90)
		(property "Reference" "SKT11"
			(at 0 0 270)
			(layer "F.SilkS")
			(hide yes)
			(effects
				(font
					(size 1.27 1.27)
				)
			)
		)
		(property "Value" "SKT-SATA14P-15P-12-GP"
			(at -22.6187 8.1788 270)
			(unlocked yes)
			(layer "F.Fab")
			(hide yes)
			(effects
				(font
					(size 1.016 1.016)
					(thickness 0.1524)
				)
			)
		)
		(property "Device Type" "87945-1001"
			(at -22.6187 6.6548 270)
			(unlocked yes)
			(layer "F.Fab")
			(hide yes)
			(effects
				(font
					(size 1.016 1.016)
					(thickness 0.1524)
				)
			)
		)
		(duplicate_pad_numbers_are_jumpers no)
		(fp_line
			(start -20.4724 9.652)
			(end -20.4724 2.3114)
			(stroke
				(width 0.1524)
				(type default)
			)
			(layer "F.SilkS")
		)
		(fp_line
			(start -17.8435 9.652)
			(end -20.4724 9.652)
			(stroke
				(width 0.1524)
				(type default)
			)
			(layer "F.SilkS")
		)
		(fp_line
			(start 17.8435 9.652)
			(end 17.8435 7.9502)
			(stroke
				(width 0.1524)
				(type default)
			)
			(layer "F.SilkS")
		)
		(fp_line
			(start 20.4724 9.652)
			(end 17.8435 9.652)
			(stroke
				(width 0.1524)
				(type default)
			)
			(layer "F.SilkS")
		)
		(fp_line
			(start -17.8435 7.9502)
			(end -17.8435 9.652)
			(stroke
				(width 0.1524)
				(type default)
			)
			(layer "F.SilkS")
		)
		(fp_line
			(start 17.8435 7.9502)
			(end -17.8435 7.9502)
			(stroke
				(width 0.1524)
				(type default)
			)
			(layer "F.SilkS")
		)
		(fp_line
			(start -23.7617 2.3114)
			(end -23.7617 -2.3114)
			(stroke
				(width 0.1524)
				(type default)
			)
			(layer "F.SilkS")
		)
		(fp_line
			(start -20.4724 2.3114)
			(end -23.7617 2.3114)
			(stroke
				(width 0.1524)
				(type default)
			)
			(layer "F.SilkS")
		)
		(fp_line
			(start 20.4724 2.3114)
			(end 20.4724 9.652)
			(stroke
				(width 0.1524)
				(type default)
			)
			(layer "F.SilkS")
		)
		(fp_line
			(start 23.7617 2.3114)
			(end 20.4724 2.3114)
			(stroke
				(width 0.1524)
				(type default)
			)
			(layer "F.SilkS")
		)
		(fp_line
			(start -23.117556 0.5461)
			(end -23.117556 -0.5461)
			(stroke
				(width 0.3048)
				(type default)
			)
			(layer "F.SilkS")
		)
		(fp_line
			(start 20.882356 0.5461)
			(end 20.882356 -0.5461)
			(stroke
				(width 0.3048)
				(type default)
			)
			(layer "F.SilkS")
		)
		(fp_line
			(start -20.882356 -0.5461)
			(end -20.882356 0.5461)
			(stroke
				(width 0.3048)
				(type default)
			)
			(layer "F.SilkS")
		)
		(fp_line
			(start 23.117556 -0.5461)
			(end 23.117556 0.5461)
			(stroke
				(width 0.3048)
				(type default)
			)
			(layer "F.SilkS")
		)
		(fp_line
			(start -23.7617 -2.3114)
			(end -20.4724 -2.3114)
			(stroke
				(width 0.1524)
				(type default)
			)
			(layer "F.SilkS")
		)
		(fp_line
			(start -20.4724 -2.3114)
			(end -20.4724 -5.7658)
			(stroke
				(width 0.1524)
				(type default)
			)
			(layer "F.SilkS")
		)
		(fp_line
			(start 20.4724 -2.3114)
			(end 23.7617 -2.3114)
			(stroke
				(width 0.1524)
				(type default)
			)
			(layer "F.SilkS")
		)
		(fp_line
			(start 23.7617 -2.3114)
			(end 23.7617 2.3114)
			(stroke
				(width 0.1524)
				(type default)
			)
			(layer "F.SilkS")
		)
		(fp_line
			(start -20.4724 -5.7658)
			(end 20.4724 -5.7658)
			(stroke
				(width 0.1524)
				(type default)
			)
			(layer "F.SilkS")
		)
		(fp_line
			(start 20.4724 -5.7658)
			(end 20.4724 -2.3114)
			(stroke
				(width 0.1524)
				(type default)
			)
			(layer "F.SilkS")
		)
		(fp_line
			(start -15.3924 -5.8547)
			(end -16.3576 -5.8547)
			(stroke
				(width 0.3302)
				(type default)
			)
			(layer "F.SilkS")
		)
		(fp_arc
			(start -20.882356 0.5461)
			(mid -21.999956 1.6637)
			(end -23.117556 0.5461)
			(stroke
				(width 0.3048)
				(type default)
			)
			(layer "F.SilkS")
		)
		(fp_arc
			(start 23.117556 0.5461)
			(mid 21.999956 1.6637)
			(end 20.882356 0.5461)
			(stroke
				(width 0.3048)
				(type default)
			)
			(layer "F.SilkS")
		)
		(fp_arc
			(start -23.117556 -0.5461)
			(mid -21.999956 -1.6637)
			(end -20.882356 -0.5461)
			(stroke
				(width 0.3048)
				(type default)
			)
			(layer "F.SilkS")
		)
		(fp_arc
			(start 20.882356 -0.5461)
			(mid 21.999956 -1.6637)
			(end 23.117556 -0.5461)
			(stroke
				(width 0.3048)
				(type default)
			)
			(layer "F.SilkS")
		)
		(fp_poly
			(pts
				(xy -15.87119 -5.838698) (xy -15.23619 -6.473698) (xy -16.50619 -6.473698)
			)
			(stroke
				(width 0)
				(type default)
			)
			(fill yes)
			(layer "F.SilkS")
		)
		(fp_poly
			(pts
				(xy -20.2184 -5.5118) (xy 20.2184 -5.5118) (xy 20.2184 -2.0574) (xy 23.5077 -2.0574) (xy 23.5077 2.0574)
				(xy 20.2184 2.0574) (xy 20.2184 9.398) (xy 18.0975 9.398) (xy 18.0975 7.6962) (xy -18.0975 7.6962)
				(xy -18.0975 9.398) (xy -20.2184 9.398) (xy -20.2184 2.0574) (xy -23.5077 2.0574) (xy -23.5077 -2.0574)
				(xy -20.2184 -2.0574)
			)
			(stroke
				(width 0)
				(type default)
			)
			(fill no)
			(layer "F.CrtYd")
		)
		(fp_poly
			(pts
				(xy -20.2184 -5.5118) (xy -20.2184 -6.0198) (xy -20.7264 -6.0198) (xy -20.7264 -2.5654) (xy -24.0157 -2.5654)
				(xy -24.0157 2.5654) (xy -20.7264 2.5654) (xy -20.7264 9.906) (xy -17.5895 9.906) (xy -17.5895 8.2042)
				(xy 17.5895 8.2042) (xy 17.5895 9.906) (xy 20.7264 9.906) (xy 20.7264 2.5654) (xy 24.0157 2.5654)
				(xy 24.0157 -2.5654) (xy 20.7264 -2.5654) (xy 20.7264 -6.0198) (xy -20.21586 -6.0198) (xy -20.21586 -5.5118)
				(xy 20.2184 -5.5118) (xy 20.2184 -2.0574) (xy 23.5077 -2.0574) (xy 23.5077 2.0574) (xy 20.2184 2.0574)
				(xy 20.2184 9.398) (xy 18.0975 9.398) (xy 18.0975 7.6962) (xy -18.0975 7.6962) (xy -18.0975 9.398)
				(xy -20.2184 9.398) (xy -20.2184 2.0574) (xy -23.5077 2.0574) (xy -23.5077 -2.0574) (xy -20.2184 -2.0574)
			)
			(stroke
				(width 0)
				(type default)
			)
			(fill no)
			(layer "F.CrtYd")
		)
		(fp_poly
			(pts
				(xy -20.7264 -6.0198) (xy -20.7264 -2.5654) (xy -24.0157 -2.5654) (xy -24.0157 2.5654) (xy -20.7264 2.5654)
				(xy -20.7264 9.906) (xy -17.5895 9.906) (xy -17.5895 8.2042) (xy 17.5895 8.2042) (xy 17.5895 9.906)
				(xy 20.7264 9.906) (xy 20.7264 2.5654) (xy 24.0157 2.5654) (xy 24.0157 -2.5654) (xy 20.7264 -2.5654)
				(xy 20.7264 -6.0198)
			)
			(stroke
				(width 0)
				(type default)
			)
			(fill no)
			(layer "F.Fab")
		)
		(pad "" np_thru_hole circle
			(at -18.999962 -2.350008 270)
			(size 0.254 0.254)
			(drill 1.8542)
			(layers "*.Cu" "*.Mask")
			(clearance 1.1557)
			(thermal_gap 1.1557)
		)
		(pad "" np_thru_hole circle
			(at 18.999962 -2.350008 270)
			(size 0.254 0.254)
			(drill 1.8542)
			(layers "*.Cu" "*.Mask")
			(clearance 1.1557)
			(thermal_gap 1.1557)
		)
		(pad "H1" thru_hole oval
			(at -21.999956 0 270)
			(size 1.524 2.6162)
			(drill oval 0.8128 1.905)
			(layers "*.Cu" "*.Mask")
			(remove_unused_layers no)
			(net "GND")
			(clearance 0.1524)
			(thermal_gap 0.1524)
		)
		(pad "H2" thru_hole oval
			(at 21.999956 0 270)
			(size 1.524 2.6162)
			(drill oval 0.8128 1.905)
			(layers "*.Cu" "*.Mask")
			(remove_unused_layers no)
			(net "GND")
			(clearance 0.1524)
			(thermal_gap 0.1524)
		)
		(pad "P1" smd rect
			(at -1.89992 -4.249928 270)
			(size 0.6604 2.3876)
			(layers "F.Cu" "F.Mask" "F.Paste")
			(net "Net_65")
		)
		(pad "P2" smd rect
			(at -0.62992 -4.249928 270)
			(size 0.6604 2.3876)
			(layers "F.Cu" "F.Mask" "F.Paste")
			(net "Net_64")
		)
		(pad "P3" smd rect
			(at 0.64008 -4.249928 270)
			(size 0.6604 2.3876)
			(layers "F.Cu" "F.Mask" "F.Paste")
			(net "Net_63")
		)
		(pad "P4" smd rect
			(at 1.91008 -4.249928 270)
			(size 0.6604 2.3876)
			(layers "F.Cu" "F.Mask" "F.Paste")
			(net "GND")
		)
		(pad "P5" smd rect
			(at 3.18008 -4.249928 270)
			(size 0.6604 2.3876)
			(layers "F.Cu" "F.Mask" "F.Paste")
			(net "HDD_PRSNT_NET10")
		)
		(pad "P6" smd rect
			(at 4.45008 -4.249928 270)
			(size 0.6604 2.3876)
			(layers "F.Cu" "F.Mask" "F.Paste")
			(net "GND")
		)
		(pad "P7" smd rect
			(at 5.72008 -4.249928 270)
			(size 0.6604 2.3876)
			(layers "F.Cu" "F.Mask" "F.Paste")
			(net "5V_PRE_10")
		)
		(pad "P8" smd rect
			(at 6.99008 -4.249928 270)
			(size 0.6604 2.3876)
			(layers "F.Cu" "F.Mask" "F.Paste")
			(net "P5V_HDD10")
		)
		(pad "P9" smd rect
			(at 8.26008 -4.249928 270)
			(size 0.6604 2.3876)
			(layers "F.Cu" "F.Mask" "F.Paste")
			(net "P5V_HDD10")
		)
		(pad "P10" smd rect
			(at 9.53008 -4.249928 270)
			(size 0.6604 2.3876)
			(layers "F.Cu" "F.Mask" "F.Paste")
			(net "GND")
		)
		(pad "P11" smd rect
			(at 10.80008 -4.249928 270)
			(size 0.6604 2.3876)
			(layers "F.Cu" "F.Mask" "F.Paste")
			(net "ACT_HDD10")
		)
		(pad "P12" smd rect
			(at 12.07008 -4.249928 270)
			(size 0.6604 2.3876)
			(layers "F.Cu" "F.Mask" "F.Paste")
			(net "GND")
		)
		(pad "P13" smd rect
			(at 13.34008 -4.249928 270)
			(size 0.6604 2.3876)
			(layers "F.Cu" "F.Mask" "F.Paste")
			(net "12V_PRE_10")
		)
		(pad "P14" smd rect
			(at 14.61008 -4.249928 270)
			(size 0.6604 2.3876)
			(layers "F.Cu" "F.Mask" "F.Paste")
			(net "P12V_HDD10")
		)
		(pad "P15" smd rect
			(at 15.88008 -4.249928 270)
			(size 0.6604 2.3876)
			(layers "F.Cu" "F.Mask" "F.Paste")
			(net "P12V_HDD10")
		)
		(pad "S1" smd rect
			(at -15.86992 -4.249928 270)
			(size 0.6604 2.3876)
			(layers "F.Cu" "F.Mask" "F.Paste")
			(net "GND")
		)
		(pad "S2" smd rect
			(at -14.59992 -4.249928 270)
			(size 0.6604 2.3876)
			(layers "F.Cu" "F.Mask" "F.Paste")
			(net "SAS2X28_A_HDD10_TX_+")
		)
		(pad "S3" smd rect
			(at -13.32992 -4.249928 270)
			(size 0.6604 2.3876)
			(layers "F.Cu" "F.Mask" "F.Paste")
			(net "SAS2X28_A_HDD10_TX_-")
		)
		(pad "S4" smd rect
			(at -12.05992 -4.249928 270)
			(size 0.6604 2.3876)
			(layers "F.Cu" "F.Mask" "F.Paste")
			(net "GND")
		)
		(pad "S5" smd rect
			(at -10.78992 -4.249928 270)
			(size 0.6604 2.3876)
			(layers "F.Cu" "F.Mask" "F.Paste")
			(net "SAS2X28_DRIVE_RX_N_A10")
		)
		(pad "S6" smd rect
			(at -9.51992 -4.249928 270)
			(size 0.6604 2.3876)
			(layers "F.Cu" "F.Mask" "F.Paste")
			(net "SAS2X28_DRIVE_RX_P_A10")
		)
		(pad "S7" smd rect
			(at -8.24992 -4.249928 270)
			(size 0.6604 2.3876)
			(layers "F.Cu" "F.Mask" "F.Paste")
			(net "GND")
		)
		(pad "S8" smd rect
			(at -7.480046 -2.100072 270)
			(size 0.508 1.905)
			(layers "F.Cu" "F.Mask" "F.Paste")
			(net "GND")
		)
		(pad "S9" smd rect
			(at -6.679946 -2.100072 270)
			(size 0.508 1.905)
			(layers "F.Cu" "F.Mask" "F.Paste")
			(net "SAS2X28_B_HDD10_TX_+")
		)
		(pad "S10" smd rect
			(at -5.8801 -2.100072 270)
			(size 0.508 1.905)
			(layers "F.Cu" "F.Mask" "F.Paste")
			(net "SAS2X28_B_HDD10_TX_-")
		)
		(pad "S11" smd rect
			(at -5.08 -2.100072 270)
			(size 0.508 1.905)
			(layers "F.Cu" "F.Mask" "F.Paste")
			(net "GND")
		)
		(pad "S12" smd rect
			(at -4.2799 -2.100072 270)
			(size 0.508 1.905)
			(layers "F.Cu" "F.Mask" "F.Paste")
			(net "SAS2X28_DRIVE_RX_N_B10")
		)
		(pad "S13" smd rect
			(at -3.480054 -2.100072 270)
			(size 0.508 1.905)
			(layers "F.Cu" "F.Mask" "F.Paste")
			(net "SAS2X28_DRIVE_RX_P_B10")
		)
		(pad "S14" smd rect
			(at -2.679954 -2.100072 270)
			(size 0.508 1.905)
			(layers "F.Cu" "F.Mask" "F.Paste")
			(net "GND")
		)
		(zone
			(layers "F.Cu" "B.Cu" "In1.Cu" "In2.Cu" "In3.Cu" "In4.Cu" "In5.Cu" "In6.Cu")
			(hatch none 0.5)
			(connect_pads
				(clearance 0)
			)
			(min_thickness 0.25)
			(keepout
				(tracks not_allowed)
				(vias allowed)
				(pads allowed)
				(copperpour not_allowed)
				(footprints allowed)
			)
			(placement
				(enabled no)
				(sheetname "")
			)
			(fill
				(thermal_gap 0.5)
				(thermal_bridge_width 0.5)
				(island_removal_mode 0)
			)
			(polygon
				(pts
					(arc
						(start 21.082 -457.330048)
						(mid 18.6182 -457.330048)
						(end 21.082 -457.330048)
					)
				)
			)
		)
		(zone
			(layers "F.Cu" "B.Cu" "In1.Cu" "In2.Cu" "In3.Cu" "In4.Cu" "In5.Cu" "In6.Cu")
			(hatch none 0.5)
			(connect_pads
				(clearance 0)
			)
			(min_thickness 0.25)
			(keepout
				(tracks not_allowed)
				(vias allowed)
				(pads allowed)
				(copperpour not_allowed)
				(footprints allowed)
			)
			(placement
				(enabled no)
				(sheetname "")
			)
			(fill
				(thermal_gap 0.5)
				(thermal_bridge_width 0.5)
				(island_removal_mode 0)
			)
			(polygon
				(pts
					(arc
						(start 21.082 -419.330124)
						(mid 18.6182 -419.330124)
						(end 21.082 -419.330124)
					)
				)
			)
		)
	)
	(footprint ""
		(layer "F.Cu")
		(at 204.088746 -379.9967)
		(property "Reference" "TP26"
			(at 0 0 0)
			(layer "F.SilkS")
			(hide yes)
			(effects
				(font
					(size 1.27 1.27)
				)
			)
		)
		(property "Value" "TPAD32-GP"
			(at 0 -3.166364 0)
			(unlocked yes)
			(layer "F.Fab")
			(hide yes)
			(effects
				(font
					(size 1.016 1.016)
					(thickness 0.1524)
				)
			)
		)
		(property "Device Type" "TPAD32"
			(at 0 -4.690618 0)
			(unlocked yes)
			(layer "F.Fab")
			(hide yes)
			(effects
				(font
					(size 1.016 1.016)
					(thickness 0.1524)
				)
			)
		)
		(duplicate_pad_numbers_are_jumpers no)
		(fp_poly
			(pts
				(arc
					(start 0.4064 0)
					(mid -0.4064 0)
					(end 0.4064 0)
				)
			)
			(stroke
				(width 0)
				(type default)
			)
			(fill no)
			(layer "F.CrtYd")
		)
		(fp_poly
			(pts
				(arc
					(start 0.7112 0)
					(mid -0.7112 0)
					(end 0.7112 0)
				)
			)
			(stroke
				(width 0)
				(type default)
			)
			(fill no)
			(layer "F.Fab")
		)
		(pad "1" smd circle
			(at 0 0)
			(size 0.8128 0.8128)
			(layers "F.Cu" "F.Mask" "F.Paste")
			(net "ACT_HDD1")
		)
	)
	(footprint ""
		(layer "F.Cu")
		(at 200.278746 -492.5187)
		(property "Reference" "U1"
			(at 0 0 0)
			(layer "F.SilkS")
			(hide yes)
			(effects
				(font
					(size 1.27 1.27)
				)
			)
		)
		(property "Value" "74LVC1G08GW-1-GP"
			(at -2.3368 -8.6868 0)
			(unlocked yes)
			(layer "F.Fab")
			(hide yes)
			(effects
				(font
					(size 1.016 1.016)
					(thickness 0.1524)
				)
			)
		)
		(property "Device Type" "SC70-5H44"
			(at -2.3114 -10.414 0)
			(unlocked yes)
			(layer "F.Fab")
			(hide yes)
			(effects
				(font
					(size 1.016 1.016)
					(thickness 0.1524)
				)
			)
		)
		(duplicate_pad_numbers_are_jumpers no)
		(fp_line
			(start -1.27 -1.7018)
			(end 1.27 -1.7018)
			(stroke
				(width 0.1524)
				(type default)
			)
			(layer "F.SilkS")
		)
		(fp_line
			(start -1.27 1.7018)
			(end -1.27 -1.7018)
			(stroke
				(width 0.1524)
				(type default)
			)
			(layer "F.SilkS")
		)
		(fp_line
			(start 0.6604 -1.8034)
			(end 1.3843 -1.8034)
			(stroke
				(width 0.3302)
				(type default)
			)
			(layer "F.SilkS")
		)
		(fp_line
			(start 1.27 -1.7018)
			(end 1.27 1.7018)
			(stroke
				(width 0.1524)
				(type default)
			)
			(layer "F.SilkS")
		)
		(fp_line
			(start 1.27 1.7018)
			(end -1.27 1.7018)
			(stroke
				(width 0.1524)
				(type default)
			)
			(layer "F.SilkS")
		)
		(fp_line
			(start 1.3843 -1.8034)
			(end 1.3843 -1.1176)
			(stroke
				(width 0.3302)
				(type default)
			)
			(layer "F.SilkS")
		)
		(fp_rect
			(start -1.524 1.9558)
			(end 1.524 -1.9558)
			(stroke
				(width 0)
				(type default)
			)
			(fill no)
			(layer "F.CrtYd")
		)
		(fp_poly
			(pts
				(xy -1.524 -1.9558) (xy 1.524 -1.9558) (xy 1.524 1.9558) (xy -1.524 1.9558)
			)
			(stroke
				(width 0)
				(type default)
			)
			(fill no)
			(layer "F.Fab")
		)
		(pad "1" smd rect
			(at 0.65024 -0.8255)
			(size 0.4064 1.2192)
			(layers "F.Cu" "F.Mask" "F.Paste")
			(net "SAS2X28_B_HDD0_FLT")
		)
		(pad "2" smd rect
			(at 0 -0.8255)
			(size 0.4064 1.2192)
			(layers "F.Cu" "F.Mask" "F.Paste")
			(net "SAS2X28_A_HDD0_FLT")
		)
		(pad "3" smd rect
			(at -0.65024 -0.8255)
			(size 0.4064 1.2192)
			(layers "F.Cu" "F.Mask" "F.Paste")
			(net "GND")
		)
		(pad "4" smd rect
			(at -0.65024 0.8255)
			(size 0.4064 1.2192)
			(layers "F.Cu" "F.Mask" "F.Paste")
			(net "FLT_HDD0_DRIVE")
		)
		(pad "5" smd rect
			(at 0.65024 0.8255)
			(size 0.4064 1.2192)
			(layers "F.Cu" "F.Mask" "F.Paste")
			(net "P3V3")
		)
	)
)
